(kicad_pcb
	(version 20260206)
	(generator "pcbnew")
	(generator_version "10.0")
	(general
		(thickness 1.6)
		(legacy_teardrops no)
	)
	(paper "A4")
	(title_block
		(title "01162023_DA0F0TEBIF0_F0T_Expander_BD_F_brd_V02_OCP.brd")
		(comment 1 "Grand Teton / footprints 6040-6046 of 9728")
	)
	(layers
		(0 "F.Cu" signal "TOP")
		(4 "In1.Cu" signal "GND")
		(6 "In2.Cu" signal "VCC")
		(8 "In3.Cu" signal "VCC1")
		(10 "In4.Cu" signal "GND1")
		(12 "In5.Cu" signal "IN1")
		(14 "In6.Cu" signal "GND2")
		(16 "In7.Cu" signal "IN2")
		(18 "In8.Cu" signal "GND3")
		(20 "In9.Cu" signal "IN3")
		(22 "In10.Cu" signal "GND4")
		(24 "In11.Cu" signal "IN4")
		(26 "In12.Cu" signal "GND5")
		(28 "In13.Cu" signal "IN5")
		(30 "In14.Cu" signal "GND6")
		(32 "In15.Cu" signal "IN6")
		(34 "In16.Cu" signal "GND7")
		(2 "B.Cu" signal "BOTTOM")
		(9 "F.Adhes" user "F.Adhesive")
		(11 "B.Adhes" user "B.Adhesive")
		(13 "F.Paste" user "Package Geometry/Pastemask Top")
		(15 "B.Paste" user "Package Geometry/Pastemask Bottom")
		(5 "F.SilkS" user "Ref Des/Silkscreen Top")
		(7 "B.SilkS" user "Ref Des/Silkscreen Bottom")
		(1 "F.Mask" user "Board Geometry/Soldermask Top")
		(3 "B.Mask" user "Board Geometry/Soldermask Bottom")
		(17 "Dwgs.User" user "User.Drawings")
		(19 "Cmts.User" user "User.Comments")
		(21 "Eco1.User" user "User.Eco1")
		(23 "Eco2.User" user "User.Eco2")
		(25 "Edge.Cuts" user "Board Geometry/Outline")
		(27 "Margin" user)
		(31 "F.CrtYd" user "Package Geometry/Place Bound Top")
		(29 "B.CrtYd" user "Package Geometry/Place Bound Bottom")
		(35 "F.Fab" user "Ref Des/Assembly Top")
		(33 "B.Fab" user "Ref Des/Assembly Bottom")
	)
	(footprint ""
		(layer "F.Cu")
		(at 385.850384 -250.070874 -90)
		(property "Reference" "R1415"
			(at 0 0 270)
			(layer "F.SilkS")
			(hide yes)
			(effects
				(font
					(size 1.27 1.27)
				)
			)
		)
		(property "Value" ""
			(at 0 0 270)
			(layer "F.Fab")
			(effects
				(font
					(size 1.27 1.27)
				)
			)
		)
		(duplicate_pad_numbers_are_jumpers no)
		(fp_line
			(start -0.7874 0.4064)
			(end -0.7874 -0.4064)
			(stroke
				(width 0.1524)
				(type default)
			)
			(layer "F.SilkS")
		)
		(fp_line
			(start 0.7874 0.4064)
			(end -0.7874 0.4064)
			(stroke
				(width 0.1524)
				(type default)
			)
			(layer "F.SilkS")
		)
		(fp_line
			(start -0.7874 -0.4064)
			(end 0.7874 -0.4064)
			(stroke
				(width 0.1524)
				(type default)
			)
			(layer "F.SilkS")
		)
		(fp_line
			(start 0.7874 -0.4064)
			(end 0.7874 0.4064)
			(stroke
				(width 0.1524)
				(type default)
			)
			(layer "F.SilkS")
		)
		(fp_line
			(start -0.67945 0.3048)
			(end -0.67945 -0.305054)
			(stroke
				(width 0.1)
				(type default)
			)
			(layer "F.Fab")
		)
		(fp_line
			(start -0.12065 0.3048)
			(end -0.67945 0.3048)
			(stroke
				(width 0.1)
				(type default)
			)
			(layer "F.Fab")
		)
		(fp_line
			(start 0.120396 0.3048)
			(end 0.120396 0.2794)
			(stroke
				(width 0.1)
				(type default)
			)
			(layer "F.Fab")
		)
		(fp_line
			(start 0.67945 0.3048)
			(end 0.120396 0.3048)
			(stroke
				(width 0.1)
				(type default)
			)
			(layer "F.Fab")
		)
		(fp_line
			(start -0.12065 0.2794)
			(end -0.12065 0.3048)
			(stroke
				(width 0.1)
				(type default)
			)
			(layer "F.Fab")
		)
		(fp_line
			(start 0.120396 0.2794)
			(end -0.12065 0.2794)
			(stroke
				(width 0.1)
				(type default)
			)
			(layer "F.Fab")
		)
		(fp_line
			(start -0.12065 -0.2794)
			(end 0.12065 -0.2794)
			(stroke
				(width 0.1)
				(type default)
			)
			(layer "F.Fab")
		)
		(fp_line
			(start 0.12065 -0.2794)
			(end 0.12065 -0.3048)
			(stroke
				(width 0.1)
				(type default)
			)
			(layer "F.Fab")
		)
		(fp_line
			(start 0.12065 -0.3048)
			(end 0.67945 -0.3048)
			(stroke
				(width 0.1)
				(type default)
			)
			(layer "F.Fab")
		)
		(fp_line
			(start 0.67945 -0.3048)
			(end 0.67945 0.3048)
			(stroke
				(width 0.1)
				(type default)
			)
			(layer "F.Fab")
		)
		(fp_line
			(start -0.67945 -0.305054)
			(end -0.12065 -0.305054)
			(stroke
				(width 0.1)
				(type default)
			)
			(layer "F.Fab")
		)
		(fp_line
			(start -0.12065 -0.305054)
			(end -0.12065 -0.2794)
			(stroke
				(width 0.1)
				(type default)
			)
			(layer "F.Fab")
		)
		(pad "1" smd circle
			(at -0.40005 0 270)
			(size 0 0)
			(layers "F.Cu" "F.Mask" "F.Paste")
			(net "PEX3_MODE_SEL10")
		)
		(pad "2" smd circle
			(at 0.40005 0 270)
			(size 0 0)
			(layers "F.Cu" "F.Mask" "F.Paste")
			(net "P1V8_PEX")
		)
	)
	(footprint ""
		(layer "F.Cu")
		(at 224.022158 -84.675472 180)
		(property "Reference" "R4353"
			(at 0 0 180)
			(layer "F.SilkS")
			(hide yes)
			(effects
				(font
					(size 1.27 1.27)
				)
			)
		)
		(property "Value" ""
			(at 0 0 180)
			(layer "F.Fab")
			(effects
				(font
					(size 1.27 1.27)
				)
			)
		)
		(duplicate_pad_numbers_are_jumpers no)
		(fp_line
			(start 0.7874 0.4064)
			(end -0.7874 0.4064)
			(stroke
				(width 0.1524)
				(type default)
			)
			(layer "F.SilkS")
		)
		(fp_line
			(start 0.7874 -0.4064)
			(end 0.7874 0.4064)
			(stroke
				(width 0.1524)
				(type default)
			)
			(layer "F.SilkS")
		)
		(fp_line
			(start -0.7874 0.4064)
			(end -0.7874 -0.4064)
			(stroke
				(width 0.1524)
				(type default)
			)
			(layer "F.SilkS")
		)
		(fp_line
			(start -0.7874 -0.4064)
			(end 0.7874 -0.4064)
			(stroke
				(width 0.1524)
				(type default)
			)
			(layer "F.SilkS")
		)
		(fp_line
			(start 0.67945 0.3048)
			(end 0.120396 0.3048)
			(stroke
				(width 0.1)
				(type default)
			)
			(layer "F.Fab")
		)
		(fp_line
			(start 0.67945 -0.3048)
			(end 0.67945 0.3048)
			(stroke
				(width 0.1)
				(type default)
			)
			(layer "F.Fab")
		)
		(fp_line
			(start 0.12065 -0.2794)
			(end 0.12065 -0.3048)
			(stroke
				(width 0.1)
				(type default)
			)
			(layer "F.Fab")
		)
		(fp_line
			(start 0.12065 -0.3048)
			(end 0.67945 -0.3048)
			(stroke
				(width 0.1)
				(type default)
			)
			(layer "F.Fab")
		)
		(fp_line
			(start 0.120396 0.3048)
			(end 0.120396 0.2794)
			(stroke
				(width 0.1)
				(type default)
			)
			(layer "F.Fab")
		)
		(fp_line
			(start 0.120396 0.2794)
			(end -0.12065 0.2794)
			(stroke
				(width 0.1)
				(type default)
			)
			(layer "F.Fab")
		)
		(fp_line
			(start -0.12065 0.3048)
			(end -0.67945 0.3048)
			(stroke
				(width 0.1)
				(type default)
			)
			(layer "F.Fab")
		)
		(fp_line
			(start -0.12065 0.2794)
			(end -0.12065 0.3048)
			(stroke
				(width 0.1)
				(type default)
			)
			(layer "F.Fab")
		)
		(fp_line
			(start -0.12065 -0.2794)
			(end 0.12065 -0.2794)
			(stroke
				(width 0.1)
				(type default)
			)
			(layer "F.Fab")
		)
		(fp_line
			(start -0.12065 -0.305054)
			(end -0.12065 -0.2794)
			(stroke
				(width 0.1)
				(type default)
			)
			(layer "F.Fab")
		)
		(fp_line
			(start -0.67945 0.3048)
			(end -0.67945 -0.305054)
			(stroke
				(width 0.1)
				(type default)
			)
			(layer "F.Fab")
		)
		(fp_line
			(start -0.67945 -0.305054)
			(end -0.12065 -0.305054)
			(stroke
				(width 0.1)
				(type default)
			)
			(layer "F.Fab")
		)
		(pad "1" smd circle
			(at -0.40005 0 180)
			(size 0 0)
			(layers "F.Cu" "F.Mask" "F.Paste")
			(net "P3V3_AUX")
		)
		(pad "2" smd circle
			(at 0.40005 0 180)
			(size 0 0)
			(layers "F.Cu" "F.Mask" "F.Paste")
			(net "SSD15_LED_R")
		)
	)
	(footprint ""
		(layer "F.Cu")
		(at 419.510972 -343.952322 90)
		(property "Reference" "C2448"
			(at 0 0 90)
			(layer "F.SilkS")
			(hide yes)
			(effects
				(font
					(size 1.27 1.27)
				)
			)
		)
		(property "Value" ""
			(at 0 0 90)
			(layer "F.Fab")
			(effects
				(font
					(size 1.27 1.27)
				)
			)
		)
		(duplicate_pad_numbers_are_jumpers no)
		(fp_line
			(start 0.299974 -0.150114)
			(end 0.299974 0.150114)
			(stroke
				(width 0.1)
				(type default)
			)
			(layer "F.Fab")
		)
		(fp_line
			(start -0.299974 -0.150114)
			(end 0.299974 -0.150114)
			(stroke
				(width 0.1)
				(type default)
			)
			(layer "F.Fab")
		)
		(fp_line
			(start 0.299974 0.150114)
			(end -0.299974 0.150114)
			(stroke
				(width 0.1)
				(type default)
			)
			(layer "F.Fab")
		)
		(fp_line
			(start -0.299974 0.150114)
			(end -0.299974 -0.150114)
			(stroke
				(width 0.1)
				(type default)
			)
			(layer "F.Fab")
		)
		(pad "1" smd rect
			(at -0.2667 0 90)
			(size 0.3048 0.381)
			(layers "F.Cu" "F.Mask" "F.Paste")
			(net "P5E_PEX3_STN4_TX_DN<75>")
		)
		(pad "2" smd rect
			(at 0.2667 0 90)
			(size 0.3048 0.381)
			(layers "F.Cu" "F.Mask" "F.Paste")
			(net "P5E_PEX3_STN4_TX_C_DN<75>")
		)
	)
	(footprint ""
		(layer "F.Cu")
		(at 142.343886 -47.92091)
		(property "Reference" "R548"
			(at 0 0 0)
			(layer "F.SilkS")
			(hide yes)
			(effects
				(font
					(size 1.27 1.27)
				)
			)
		)
		(property "Value" ""
			(at 0 0 0)
			(layer "F.Fab")
			(effects
				(font
					(size 1.27 1.27)
				)
			)
		)
		(duplicate_pad_numbers_are_jumpers no)
		(fp_line
			(start -0.7874 -0.4064)
			(end 0.7874 -0.4064)
			(stroke
				(width 0.1524)
				(type default)
			)
			(layer "F.SilkS")
		)
		(fp_line
			(start -0.7874 0.4064)
			(end -0.7874 -0.4064)
			(stroke
				(width 0.1524)
				(type default)
			)
			(layer "F.SilkS")
		)
		(fp_line
			(start 0.7874 -0.4064)
			(end 0.7874 0.4064)
			(stroke
				(width 0.1524)
				(type default)
			)
			(layer "F.SilkS")
		)
		(fp_line
			(start 0.7874 0.4064)
			(end -0.7874 0.4064)
			(stroke
				(width 0.1524)
				(type default)
			)
			(layer "F.SilkS")
		)
		(fp_line
			(start -0.67945 -0.305054)
			(end -0.12065 -0.305054)
			(stroke
				(width 0.1)
				(type default)
			)
			(layer "F.Fab")
		)
		(fp_line
			(start -0.67945 0.3048)
			(end -0.67945 -0.305054)
			(stroke
				(width 0.1)
				(type default)
			)
			(layer "F.Fab")
		)
		(fp_line
			(start -0.12065 -0.305054)
			(end -0.12065 -0.2794)
			(stroke
				(width 0.1)
				(type default)
			)
			(layer "F.Fab")
		)
		(fp_line
			(start -0.12065 -0.2794)
			(end 0.12065 -0.2794)
			(stroke
				(width 0.1)
				(type default)
			)
			(layer "F.Fab")
		)
		(fp_line
			(start -0.12065 0.2794)
			(end -0.12065 0.3048)
			(stroke
				(width 0.1)
				(type default)
			)
			(layer "F.Fab")
		)
		(fp_line
			(start -0.12065 0.3048)
			(end -0.67945 0.3048)
			(stroke
				(width 0.1)
				(type default)
			)
			(layer "F.Fab")
		)
		(fp_line
			(start 0.120396 0.2794)
			(end -0.12065 0.2794)
			(stroke
				(width 0.1)
				(type default)
			)
			(layer "F.Fab")
		)
		(fp_line
			(start 0.120396 0.3048)
			(end 0.120396 0.2794)
			(stroke
				(width 0.1)
				(type default)
			)
			(layer "F.Fab")
		)
		(fp_line
			(start 0.12065 -0.3048)
			(end 0.67945 -0.3048)
			(stroke
				(width 0.1)
				(type default)
			)
			(layer "F.Fab")
		)
		(fp_line
			(start 0.12065 -0.2794)
			(end 0.12065 -0.3048)
			(stroke
				(width 0.1)
				(type default)
			)
			(layer "F.Fab")
		)
		(fp_line
			(start 0.67945 -0.3048)
			(end 0.67945 0.3048)
			(stroke
				(width 0.1)
				(type default)
			)
			(layer "F.Fab")
		)
		(fp_line
			(start 0.67945 0.3048)
			(end 0.120396 0.3048)
			(stroke
				(width 0.1)
				(type default)
			)
			(layer "F.Fab")
		)
		(pad "1" smd circle
			(at -0.40005 0)
			(size 0 0)
			(layers "F.Cu" "F.Mask" "F.Paste")
			(net "P3V3_AUX")
		)
		(pad "2" smd circle
			(at 0.40005 0)
			(size 0 0)
			(layers "F.Cu" "F.Mask" "F.Paste")
			(net "SSD_0_7_ADC_ALERT_N")
		)
	)
	(footprint ""
		(layer "F.Cu")
		(at 260.249162 -300.197012 -90)
		(property "Reference" "C3364"
			(at 0 0 270)
			(layer "F.SilkS")
			(hide yes)
			(effects
				(font
					(size 1.27 1.27)
				)
			)
		)
		(property "Value" ""
			(at 0 0 270)
			(layer "F.Fab")
			(effects
				(font
					(size 1.27 1.27)
				)
			)
		)
		(duplicate_pad_numbers_are_jumpers no)
		(fp_line
			(start -0.299974 0.150114)
			(end -0.299974 -0.150114)
			(stroke
				(width 0.1)
				(type default)
			)
			(layer "F.Fab")
		)
		(fp_line
			(start 0.299974 0.150114)
			(end -0.299974 0.150114)
			(stroke
				(width 0.1)
				(type default)
			)
			(layer "F.Fab")
		)
		(fp_line
			(start -0.299974 -0.150114)
			(end 0.299974 -0.150114)
			(stroke
				(width 0.1)
				(type default)
			)
			(layer "F.Fab")
		)
		(fp_line
			(start 0.299974 -0.150114)
			(end 0.299974 0.150114)
			(stroke
				(width 0.1)
				(type default)
			)
			(layer "F.Fab")
		)
		(pad "1" smd rect
			(at -0.2667 0 270)
			(size 0.3048 0.381)
			(layers "F.Cu" "F.Mask" "F.Paste")
			(net "P1V8_PLL0_PEX2")
		)
		(pad "2" smd rect
			(at 0.2667 0 270)
			(size 0.3048 0.381)
			(layers "F.Cu" "F.Mask" "F.Paste")
			(net "GND")
		)
	)
	(footprint ""
		(layer "F.Cu")
		(at 337.349084 -356.244906 90)
		(property "Reference" "C575"
			(at 0 0 90)
			(layer "F.SilkS")
			(hide yes)
			(effects
				(font
					(size 1.27 1.27)
				)
			)
		)
		(property "Value" ""
			(at 0 0 90)
			(layer "F.Fab")
			(effects
				(font
					(size 1.27 1.27)
				)
			)
		)
		(duplicate_pad_numbers_are_jumpers no)
		(fp_line
			(start 0.299974 -0.150114)
			(end 0.299974 0.150114)
			(stroke
				(width 0.1)
				(type default)
			)
			(layer "F.Fab")
		)
		(fp_line
			(start -0.299974 -0.150114)
			(end 0.299974 -0.150114)
			(stroke
				(width 0.1)
				(type default)
			)
			(layer "F.Fab")
		)
		(fp_line
			(start 0.299974 0.150114)
			(end -0.299974 0.150114)
			(stroke
				(width 0.1)
				(type default)
			)
			(layer "F.Fab")
		)
		(fp_line
			(start -0.299974 0.150114)
			(end -0.299974 -0.150114)
			(stroke
				(width 0.1)
				(type default)
			)
			(layer "F.Fab")
		)
		(pad "1" smd rect
			(at -0.2667 0 90)
			(size 0.3048 0.381)
			(layers "F.Cu" "F.Mask" "F.Paste")
			(net "P5E_PEX2_STN6_TX_DP<99>")
		)
		(pad "2" smd rect
			(at 0.2667 0 90)
			(size 0.3048 0.381)
			(layers "F.Cu" "F.Mask" "F.Paste")
			(net "P5E_PEX2_STN6_TX_C_DP<99>")
		)
	)
	(footprint ""
		(layer "F.Cu")
		(at 33.287716 -285.218632)
		(property "Reference" "C3058"
			(at 0 0 0)
			(layer "F.SilkS")
			(hide yes)
			(effects
				(font
					(size 1.27 1.27)
				)
			)
		)
		(property "Value" ""
			(at 0 0 0)
			(layer "F.Fab")
			(effects
				(font
					(size 1.27 1.27)
				)
			)
		)
		(duplicate_pad_numbers_are_jumpers no)
		(fp_line
			(start -1.2954 -0.5842)
			(end 1.2954 -0.5842)
			(stroke
				(width 0.1524)
				(type default)
			)
			(layer "F.SilkS")
		)
		(fp_line
			(start -1.2954 0.5842)
			(end -1.2954 -0.5842)
			(stroke
				(width 0.1524)
				(type default)
			)
			(layer "F.SilkS")
		)
		(fp_line
			(start 1.2954 -0.5842)
			(end 1.2954 0.5842)
			(stroke
				(width 0.1524)
				(type default)
			)
			(layer "F.SilkS")
		)
		(fp_line
			(start 1.2954 0.5842)
			(end -1.2954 0.5842)
			(stroke
				(width 0.1524)
				(type default)
			)
			(layer "F.SilkS")
		)
		(fp_line
			(start -1.1938 -0.4064)
			(end -0.8636 -0.4064)
			(stroke
				(width 0.1)
				(type default)
			)
			(layer "F.Fab")
		)
		(fp_line
			(start -1.1938 0.4064)
			(end -1.1938 -0.4064)
			(stroke
				(width 0.1)
				(type default)
			)
			(layer "F.Fab")
		)
		(fp_line
			(start -0.8636 -0.4572)
			(end 0.8636 -0.4572)
			(stroke
				(width 0.1)
				(type default)
			)
			(layer "F.Fab")
		)
		(fp_line
			(start -0.8636 -0.4064)
			(end -0.8636 -0.4572)
			(stroke
				(width 0.1)
				(type default)
			)
			(layer "F.Fab")
		)
		(fp_line
			(start -0.8636 0.4064)
			(end -1.1938 0.4064)
			(stroke
				(width 0.1)
				(type default)
			)
			(layer "F.Fab")
		)
		(fp_line
			(start -0.8636 0.4572)
			(end -0.8636 0.4064)
			(stroke
				(width 0.1)
				(type default)
			)
			(layer "F.Fab")
		)
		(fp_line
			(start 0.8636 -0.4572)
			(end 0.8636 -0.4064)
			(stroke
				(width 0.1)
				(type default)
			)
			(layer "F.Fab")
		)
		(fp_line
			(start 0.8636 -0.4064)
			(end 1.1938 -0.4064)
			(stroke
				(width 0.1)
				(type default)
			)
			(layer "F.Fab")
		)
		(fp_line
			(start 0.8636 0.4064)
			(end 0.8636 0.4572)
			(stroke
				(width 0.1)
				(type default)
			)
			(layer "F.Fab")
		)
		(fp_line
			(start 0.8636 0.4572)
			(end -0.8636 0.4572)
			(stroke
				(width 0.1)
				(type default)
			)
			(layer "F.Fab")
		)
		(fp_line
			(start 1.1938 -0.4064)
			(end 1.1938 0.4064)
			(stroke
				(width 0.1)
				(type default)
			)
			(layer "F.Fab")
		)
		(fp_line
			(start 1.1938 0.4064)
			(end 0.8636 0.4064)
			(stroke
				(width 0.1)
				(type default)
			)
			(layer "F.Fab")
		)
		(pad "1" smd rect
			(at -0.7366 0 270)
			(size 0.7112 0.8128)
			(layers "F.Cu" "F.Mask" "F.Paste")
			(net "PCEPLL7_VDDA18_PEX0")
		)
		(pad "2" smd rect
			(at 0.7366 0 270)
			(size 0.7112 0.8128)
			(layers "F.Cu" "F.Mask" "F.Paste")
			(net "GND")
		)
	)
)
